(kicad_pcb
	(version 20260206)
	(generator "pcbnew")
	(generator_version "10.0")
	(general
		(thickness 1.6)
		(legacy_teardrops no)
	)
	(paper "A4")
	(title_block
		(title "Bryce Canyon_F.DPB_16315-1-OCP.brd")
		(comment 1 "Bryce Canyon / footprints 1282-1287 of 2223")
	)
	(layers
		(0 "F.Cu" signal "TOP")
		(4 "In1.Cu" signal "L2GND")
		(6 "In2.Cu" signal "L3")
		(8 "In3.Cu" signal "L4GND")
		(10 "In4.Cu" signal "L5")
		(12 "In5.Cu" signal "L6VCC")
		(14 "In6.Cu" signal "L7VCC")
		(16 "In7.Cu" signal "L8")
		(18 "In8.Cu" signal "L9GND")
		(20 "In9.Cu" signal "L10")
		(22 "In10.Cu" signal "L11GND")
		(2 "B.Cu" signal "BOTTOM")
		(9 "F.Adhes" user "F.Adhesive")
		(11 "B.Adhes" user "B.Adhesive")
		(13 "F.Paste" user "Package Geometry/Pastemask Top")
		(15 "B.Paste" user "Package Geometry/Pastemask Bottom")
		(5 "F.SilkS" user "Ref Des/Silkscreen Top")
		(7 "B.SilkS" user "Ref Des/Silkscreen Bottom")
		(1 "F.Mask" user "Board Geometry/Soldermask Top")
		(3 "B.Mask" user "Board Geometry/Soldermask Bottom")
		(17 "Dwgs.User" user "User.Drawings")
		(19 "Cmts.User" user "User.Comments")
		(21 "Eco1.User" user "User.Eco1")
		(23 "Eco2.User" user "User.Eco2")
		(25 "Edge.Cuts" user "Board Geometry/Outline")
		(27 "Margin" user)
		(31 "F.CrtYd" user "Package Geometry/Place Bound Top")
		(29 "B.CrtYd" user "Package Geometry/Place Bound Bottom")
		(35 "F.Fab" user "Ref Des/Assembly Top")
		(33 "B.Fab" user "Ref Des/Assembly Bottom")
	)
	(footprint ""
		(layer "F.Cu")
		(at 172.593 -53.482494 -90)
		(property "Reference" "R812"
			(at 0 0 270)
			(layer "F.SilkS")
			(hide yes)
			(effects
				(font
					(size 1.27 1.27)
				)
			)
		)
		(property "Value" "300KR2F-GP"
			(at 0.064008 -3.993896 270)
			(unlocked yes)
			(layer "F.Fab")
			(hide yes)
			(effects
				(font
					(size 1.016 1.016)
					(thickness 0.1524)
				)
			)
		)
		(property "Device Type" "R402H16"
			(at 0.064008 -5.517896 270)
			(unlocked yes)
			(layer "F.Fab")
			(hide yes)
			(effects
				(font
					(size 1.016 1.016)
					(thickness 0.1524)
				)
			)
		)
		(duplicate_pad_numbers_are_jumpers no)
		(fp_line
			(start -0.508 -0.9398)
			(end -0.508 0.9398)
			(stroke
				(width 0.1524)
				(type default)
			)
			(layer "F.SilkS")
		)
		(fp_line
			(start 0.508 -0.9398)
			(end -0.508 -0.9398)
			(stroke
				(width 0.1524)
				(type default)
			)
			(layer "F.SilkS")
		)
		(fp_rect
			(start -0.508 0.9398)
			(end 0.508 -0.9398)
			(stroke
				(width 0)
				(type default)
			)
			(fill no)
			(layer "F.CrtYd")
		)
		(fp_rect
			(start -0.508 0.9398)
			(end 0.508 -0.9398)
			(stroke
				(width 0)
				(type default)
			)
			(fill no)
			(layer "F.Fab")
		)
		(pad "1" smd custom
			(at 0 -0.4445 270)
			(size 0.1397 0.1397)
			(layers "F.Cu" "F.Mask" "F.Paste")
			(net "SW_HDD_N29")
			(options
				(clearance outline)
				(anchor circle)
			)
			(primitives
				(gr_poly
					(pts
						(arc
							(start -0.1778 -0.2794)
							(mid -0.249642 -0.249642)
							(end -0.2794 -0.1778)
						)
						(arc
							(start -0.2794 0.1778)
							(mid -0.249642 0.249642)
							(end -0.1778 0.2794)
						)
						(arc
							(start 0.1778 0.2794)
							(mid 0.249642 0.249642)
							(end 0.2794 0.1778)
						)
						(arc
							(start 0.2794 -0.1778)
							(mid 0.249642 -0.249642)
							(end 0.1778 -0.2794)
						)
					)
					(width 0)
					(fill yes)
				)
			)
		)
		(pad "2" smd custom
			(at 0 0.4445 270)
			(size 0.1397 0.1397)
			(layers "F.Cu" "F.Mask" "F.Paste")
			(net "P12V_A")
			(options
				(clearance outline)
				(anchor circle)
			)
			(primitives
				(gr_poly
					(pts
						(arc
							(start -0.1778 -0.2794)
							(mid -0.249642 -0.249642)
							(end -0.2794 -0.1778)
						)
						(arc
							(start -0.2794 0.1778)
							(mid -0.249642 0.249642)
							(end -0.1778 0.2794)
						)
						(arc
							(start 0.1778 0.2794)
							(mid 0.249642 0.249642)
							(end 0.2794 0.1778)
						)
						(arc
							(start 0.2794 -0.1778)
							(mid 0.249642 -0.249642)
							(end 0.1778 -0.2794)
						)
					)
					(width 0)
					(fill yes)
				)
			)
		)
	)
	(footprint ""
		(layer "F.Cu")
		(at 159.324802 -322.799964)
		(property "Reference" ""
			(at 0 0 0)
			(layer "F.SilkS")
			(hide yes)
			(effects
				(font
					(size 1.27 1.27)
				)
			)
		)
		(property "Value" "*"
			(at -8.398764 -8.057642 0)
			(unlocked yes)
			(layer "F.Fab")
			(hide yes)
			(effects
				(font
					(size 1.016 1.016)
					(thickness 0.1524)
				)
			)
		)
		(duplicate_pad_numbers_are_jumpers no)
		(fp_poly
			(pts
				(arc
					(start 7.3152 0)
					(mid 0 7.3152)
					(end -7.3152 0)
				)
				(arc
					(start -7.3152 -5.9944)
					(mid 0 -13.3096)
					(end 7.3152 -5.9944)
				)
			)
			(stroke
				(width 0)
				(type default)
			)
			(fill no)
			(layer "B.CrtYd")
		)
		(fp_poly
			(pts
				(arc
					(start 7.3152 0)
					(mid 0 7.3152)
					(end -7.3152 0)
				)
				(arc
					(start -7.3152 -5.9944)
					(mid 0 -13.3096)
					(end 7.3152 -5.9944)
				)
			)
			(stroke
				(width 0)
				(type default)
			)
			(fill no)
			(layer "F.CrtYd")
		)
		(fp_poly
			(pts
				(arc
					(start 7.3152 0)
					(mid 0 7.3152)
					(end -7.3152 0)
				)
				(arc
					(start -7.3152 -5.9944)
					(mid 0 -13.3096)
					(end 7.3152 -5.9944)
				)
			)
			(stroke
				(width 0)
				(type default)
			)
			(fill no)
			(layer "B.Fab")
		)
		(fp_poly
			(pts
				(arc
					(start 7.3152 0)
					(mid 0 7.3152)
					(end -7.3152 0)
				)
				(arc
					(start -7.3152 -5.9944)
					(mid 0 -13.3096)
					(end 7.3152 -5.9944)
				)
			)
			(stroke
				(width 0)
				(type default)
			)
			(fill no)
			(layer "F.Fab")
		)
		(pad "1" thru_hole oval
			(at 0 0)
			(size 14.0208 20.0152)
			(drill 0.0254
				(offset 0 -2.9972)
			)
			(layers "*.Cu" "*.Mask")
			(remove_unused_layers no)
			(net "Net_107")
			(clearance -1.002284)
			(thermal_gap 0.1524)
			(padstack
				(mode front_inner_back)
				(layer "Inner"
					(shape custom)
					(size 2.928012 2.928012)
					(options
						(anchor circle)
					)
					(primitives
						(gr_poly
							(pts
								(arc
									(start 4.571746 -2.084324)
									(mid 0.000333 7.430372)
									(end -4.571492 -2.084324)
								)
								(arc
									(start -4.571492 -2.084324)
									(mid -3.570296 -3.611977)
									(end -2.875026 -5.30098)
								)
								(arc
									(start -2.875026 -5.30098)
									(mid 0.000217 -7.43089)
									(end 2.87528 -5.30098)
								)
								(arc
									(start 2.87528 -5.30098)
									(mid 3.570511 -3.611956)
									(end 4.571746 -2.084324)
								)
							)
							(width 0)
							(fill yes)
						)
					)
					(clearance 0.1524)
				)
				(layer "B.Cu"
					(shape oval)
					(size 14.0208 20.0152)
					(offset 0 -2.9972)
					(clearance -1.002284)
				)
			)
		)
		(zone
			(layers "F.Cu" "B.Cu" "In1.Cu" "In2.Cu" "In3.Cu" "In4.Cu" "In5.Cu" "In6.Cu"
				"In7.Cu" "In8.Cu" "In9.Cu" "In10.Cu"
			)
			(hatch none 0.5)
			(connect_pads
				(clearance 0)
			)
			(min_thickness 0.25)
			(keepout
				(tracks not_allowed)
				(vias allowed)
				(pads allowed)
				(copperpour not_allowed)
				(footprints allowed)
			)
			(placement
				(enabled no)
				(sheetname "")
			)
			(fill
				(thermal_gap 0.5)
				(thermal_bridge_width 0.5)
				(island_removal_mode 0)
			)
			(polygon
				(pts
					(arc
						(start 152.314402 -328.794364)
						(mid 159.324802 -335.804764)
						(end 166.335202 -328.794364)
					)
					(arc
						(start 166.335202 -322.799964)
						(mid 159.324802 -315.789564)
						(end 152.314402 -322.799964)
					)
				)
			)
		)
	)
	(footprint ""
		(layer "F.Cu")
		(at 149.196298 -46.065694 -90)
		(property "Reference" "R782"
			(at 0 0 270)
			(layer "F.SilkS")
			(hide yes)
			(effects
				(font
					(size 1.27 1.27)
				)
			)
		)
		(property "Value" "1KR2F-3-GP"
			(at 0.064008 -3.993896 270)
			(unlocked yes)
			(layer "F.Fab")
			(hide yes)
			(effects
				(font
					(size 1.016 1.016)
					(thickness 0.1524)
				)
			)
		)
		(property "Device Type" "R402H16"
			(at 0.064008 -5.517896 270)
			(unlocked yes)
			(layer "F.Fab")
			(hide yes)
			(effects
				(font
					(size 1.016 1.016)
					(thickness 0.1524)
				)
			)
		)
		(duplicate_pad_numbers_are_jumpers no)
		(fp_line
			(start -0.508 -0.9398)
			(end -0.508 0.9398)
			(stroke
				(width 0.1524)
				(type default)
			)
			(layer "F.SilkS")
		)
		(fp_line
			(start 0.508 -0.9398)
			(end -0.508 -0.9398)
			(stroke
				(width 0.1524)
				(type default)
			)
			(layer "F.SilkS")
		)
		(fp_rect
			(start -0.508 0.9398)
			(end 0.508 -0.9398)
			(stroke
				(width 0)
				(type default)
			)
			(fill no)
			(layer "F.CrtYd")
		)
		(fp_rect
			(start -0.508 0.9398)
			(end 0.508 -0.9398)
			(stroke
				(width 0)
				(type default)
			)
			(fill no)
			(layer "F.Fab")
		)
		(pad "1" smd custom
			(at 0 -0.4445 270)
			(size 0.1397 0.1397)
			(layers "F.Cu" "F.Mask" "F.Paste")
			(net "P3V3_STBY_A")
			(options
				(clearance outline)
				(anchor circle)
			)
			(primitives
				(gr_poly
					(pts
						(arc
							(start -0.1778 -0.2794)
							(mid -0.249642 -0.249642)
							(end -0.2794 -0.1778)
						)
						(arc
							(start -0.2794 0.1778)
							(mid -0.249642 0.249642)
							(end -0.1778 0.2794)
						)
						(arc
							(start 0.1778 0.2794)
							(mid 0.249642 0.249642)
							(end 0.2794 0.1778)
						)
						(arc
							(start 0.2794 -0.1778)
							(mid 0.249642 -0.249642)
							(end 0.1778 -0.2794)
						)
					)
					(width 0)
					(fill yes)
				)
			)
		)
		(pad "2" smd custom
			(at 0 0.4445 270)
			(size 0.1397 0.1397)
			(layers "F.Cu" "F.Mask" "F.Paste")
			(net "SW_PWR_R_HDD28")
			(options
				(clearance outline)
				(anchor circle)
			)
			(primitives
				(gr_poly
					(pts
						(arc
							(start -0.1778 -0.2794)
							(mid -0.249642 -0.249642)
							(end -0.2794 -0.1778)
						)
						(arc
							(start -0.2794 0.1778)
							(mid -0.249642 0.249642)
							(end -0.1778 0.2794)
						)
						(arc
							(start 0.1778 0.2794)
							(mid 0.249642 0.249642)
							(end 0.2794 0.1778)
						)
						(arc
							(start 0.2794 -0.1778)
							(mid 0.249642 -0.249642)
							(end 0.1778 -0.2794)
						)
					)
					(width 0)
					(fill yes)
				)
			)
		)
	)
	(footprint ""
		(layer "F.Cu")
		(at 478.620328 -267.773658 90)
		(property "Reference" "R387"
			(at 0 0 90)
			(layer "F.SilkS")
			(hide yes)
			(effects
				(font
					(size 1.27 1.27)
				)
			)
		)
		(property "Value" "220R3F-1-GP"
			(at -0.0254 -2.5146 90)
			(unlocked yes)
			(layer "F.Fab")
			(hide yes)
			(effects
				(font
					(size 1.016 1.016)
					(thickness 0.1524)
				)
			)
		)
		(property "Device Type" "R603H22"
			(at -0.0254 -4.0386 90)
			(unlocked yes)
			(layer "F.Fab")
			(hide yes)
			(effects
				(font
					(size 1.016 1.016)
					(thickness 0.1524)
				)
			)
		)
		(duplicate_pad_numbers_are_jumpers no)
		(fp_line
			(start 0.2032 0)
			(end 0.4826 0)
			(stroke
				(width 0.2032)
				(type default)
			)
			(layer "F.SilkS")
		)
		(fp_line
			(start -0.4826 0)
			(end -0.2032 0)
			(stroke
				(width 0.2032)
				(type default)
			)
			(layer "F.SilkS")
		)
		(fp_rect
			(start -0.5842 1.3335)
			(end 0.5842 -1.3335)
			(stroke
				(width 0)
				(type default)
			)
			(fill no)
			(layer "F.CrtYd")
		)
		(fp_rect
			(start -0.5842 1.3335)
			(end 0.5842 -1.3335)
			(stroke
				(width 0)
				(type default)
			)
			(fill no)
			(layer "F.Fab")
		)
		(pad "1" smd custom
			(at 0 -0.762 90)
			(size 0.2159 0.2159)
			(layers "F.Cu" "F.Mask" "F.Paste")
			(net "HDD_PRSNT_11")
			(options
				(clearance outline)
				(anchor circle)
			)
			(primitives
				(gr_poly
					(pts
						(arc
							(start -0.3302 -0.4318)
							(mid -0.402042 -0.402042)
							(end -0.4318 -0.3302)
						)
						(arc
							(start -0.4318 0.3302)
							(mid -0.402042 0.402042)
							(end -0.3302 0.4318)
						)
						(arc
							(start 0.3302 0.4318)
							(mid 0.402042 0.402042)
							(end 0.4318 0.3302)
						)
						(arc
							(start 0.4318 -0.3302)
							(mid 0.402042 -0.402042)
							(end 0.3302 -0.4318)
						)
					)
					(width 0)
					(fill yes)
				)
			)
		)
		(pad "2" smd custom
			(at 0 0.762 90)
			(size 0.2159 0.2159)
			(layers "F.Cu" "F.Mask" "F.Paste")
			(net "DRIVE_A_11_INS")
			(options
				(clearance outline)
				(anchor circle)
			)
			(primitives
				(gr_poly
					(pts
						(arc
							(start -0.3302 -0.4318)
							(mid -0.402042 -0.402042)
							(end -0.4318 -0.3302)
						)
						(arc
							(start -0.4318 0.3302)
							(mid -0.402042 0.402042)
							(end -0.3302 0.4318)
						)
						(arc
							(start 0.3302 0.4318)
							(mid 0.402042 0.402042)
							(end 0.4318 0.3302)
						)
						(arc
							(start 0.4318 -0.3302)
							(mid 0.402042 -0.402042)
							(end 0.3302 -0.4318)
						)
					)
					(width 0)
					(fill yes)
				)
			)
		)
	)
	(footprint ""
		(layer "F.Cu")
		(at 393.674854 -207.79994)
		(property "Reference" ""
			(at 0 0 0)
			(layer "F.SilkS")
			(hide yes)
			(effects
				(font
					(size 1.27 1.27)
				)
			)
		)
		(property "Value" "*"
			(at -8.398764 -8.057642 0)
			(unlocked yes)
			(layer "F.Fab")
			(hide yes)
			(effects
				(font
					(size 1.016 1.016)
					(thickness 0.1524)
				)
			)
		)
		(duplicate_pad_numbers_are_jumpers no)
		(fp_poly
			(pts
				(arc
					(start 7.3152 0)
					(mid 0 7.3152)
					(end -7.3152 0)
				)
				(arc
					(start -7.3152 -5.9944)
					(mid 0 -13.3096)
					(end 7.3152 -5.9944)
				)
			)
			(stroke
				(width 0)
				(type default)
			)
			(fill no)
			(layer "B.CrtYd")
		)
		(fp_poly
			(pts
				(arc
					(start 7.3152 0)
					(mid 0 7.3152)
					(end -7.3152 0)
				)
				(arc
					(start -7.3152 -5.9944)
					(mid 0 -13.3096)
					(end 7.3152 -5.9944)
				)
			)
			(stroke
				(width 0)
				(type default)
			)
			(fill no)
			(layer "F.CrtYd")
		)
		(fp_poly
			(pts
				(arc
					(start 7.3152 0)
					(mid 0 7.3152)
					(end -7.3152 0)
				)
				(arc
					(start -7.3152 -5.9944)
					(mid 0 -13.3096)
					(end 7.3152 -5.9944)
				)
			)
			(stroke
				(width 0)
				(type default)
			)
			(fill no)
			(layer "B.Fab")
		)
		(fp_poly
			(pts
				(arc
					(start 7.3152 0)
					(mid 0 7.3152)
					(end -7.3152 0)
				)
				(arc
					(start -7.3152 -5.9944)
					(mid 0 -13.3096)
					(end 7.3152 -5.9944)
				)
			)
			(stroke
				(width 0)
				(type default)
			)
			(fill no)
			(layer "F.Fab")
		)
		(pad "1" thru_hole oval
			(at 0 0)
			(size 14.0208 20.0152)
			(drill 0.0254
				(offset 0 -2.9972)
			)
			(layers "*.Cu" "*.Mask")
			(remove_unused_layers no)
			(net "Net_99")
			(clearance -1.002284)
			(thermal_gap 0.1524)
			(padstack
				(mode front_inner_back)
				(layer "Inner"
					(shape custom)
					(size 2.928012 2.928012)
					(options
						(anchor circle)
					)
					(primitives
						(gr_poly
							(pts
								(arc
									(start 4.571746 -2.084324)
									(mid 0.000333 7.430372)
									(end -4.571492 -2.084324)
								)
								(arc
									(start -4.571492 -2.084324)
									(mid -3.570296 -3.611977)
									(end -2.875026 -5.30098)
								)
								(arc
									(start -2.875026 -5.30098)
									(mid 0.000217 -7.43089)
									(end 2.87528 -5.30098)
								)
								(arc
									(start 2.87528 -5.30098)
									(mid 3.570511 -3.611956)
									(end 4.571746 -2.084324)
								)
							)
							(width 0)
							(fill yes)
						)
					)
					(clearance 0.1524)
				)
				(layer "B.Cu"
					(shape oval)
					(size 14.0208 20.0152)
					(offset 0 -2.9972)
					(clearance -1.002284)
				)
			)
		)
		(zone
			(layers "F.Cu" "B.Cu" "In1.Cu" "In2.Cu" "In3.Cu" "In4.Cu" "In5.Cu" "In6.Cu"
				"In7.Cu" "In8.Cu" "In9.Cu" "In10.Cu"
			)
			(hatch none 0.5)
			(connect_pads
				(clearance 0)
			)
			(min_thickness 0.25)
			(keepout
				(tracks not_allowed)
				(vias allowed)
				(pads allowed)
				(copperpour not_allowed)
				(footprints allowed)
			)
			(placement
				(enabled no)
				(sheetname "")
			)
			(fill
				(thermal_gap 0.5)
				(thermal_bridge_width 0.5)
				(island_removal_mode 0)
			)
			(polygon
				(pts
					(arc
						(start 386.664454 -213.79434)
						(mid 393.674854 -220.80474)
						(end 400.685254 -213.79434)
					)
					(arc
						(start 400.685254 -207.79994)
						(mid 393.674854 -200.78954)
						(end 386.664454 -207.79994)
					)
				)
			)
		)
	)
	(footprint ""
		(layer "F.Cu")
		(at 474.30182 -274.193 90)
		(property "Reference" "Q67"
			(at 0 0 90)
			(layer "F.SilkS")
			(hide yes)
			(effects
				(font
					(size 1.27 1.27)
				)
			)
		)
		(property "Value" "2N7002KDW-GP"
			(at -2.3622 -8.2042 90)
			(unlocked yes)
			(layer "F.Fab")
			(hide yes)
			(effects
				(font
					(size 1.016 1.016)
					(thickness 0.1524)
				)
			)
		)
		(property "Device Type" "SOT-363H44"
			(at -2.3622 -10.1092 90)
			(unlocked yes)
			(layer "F.Fab")
			(hide yes)
			(effects
				(font
					(size 1.016 1.016)
					(thickness 0.1524)
				)
			)
		)
		(duplicate_pad_numbers_are_jumpers no)
		(fp_line
			(start 1.4478 -1.7018)
			(end -1.4478 -1.7018)
			(stroke
				(width 0.1524)
				(type default)
			)
			(layer "F.SilkS")
		)
		(fp_line
			(start -1.4478 -1.7018)
			(end -1.4478 1.7018)
			(stroke
				(width 0.1524)
				(type default)
			)
			(layer "F.SilkS")
		)
		(fp_line
			(start -1.27 1.524)
			(end -1.27 0.6604)
			(stroke
				(width 0.4826)
				(type default)
			)
			(layer "F.SilkS")
		)
		(fp_line
			(start 1.4478 1.7018)
			(end 1.4478 -1.7018)
			(stroke
				(width 0.1524)
				(type default)
			)
			(layer "F.SilkS")
		)
		(fp_line
			(start -1.4478 1.7018)
			(end 1.4478 1.7018)
			(stroke
				(width 0.1524)
				(type default)
			)
			(layer "F.SilkS")
		)
		(fp_poly
			(pts
				(xy -1.524 -1.778) (xy 1.524 -1.778) (xy 1.524 1.778) (xy -1.524 1.778)
			)
			(stroke
				(width 0)
				(type default)
			)
			(fill no)
			(layer "F.CrtYd")
		)
		(fp_poly
			(pts
				(xy -1.524 -1.778) (xy 1.524 -1.778) (xy 1.524 1.778) (xy -1.524 1.778)
			)
			(stroke
				(width 0)
				(type default)
			)
			(fill no)
			(layer "F.Fab")
		)
		(pad "1" smd rect
			(at -0.65024 0.9398 90)
			(size 0.4064 1.016)
			(layers "F.Cu" "F.Mask" "F.Paste")
			(net "GND")
		)
		(pad "2" smd rect
			(at 0 0.9398 90)
			(size 0.4064 1.016)
			(layers "F.Cu" "F.Mask" "F.Paste")
			(net "SW_PWR_R_HDD11")
		)
		(pad "3" smd rect
			(at 0.65024 0.9398 90)
			(size 0.4064 1.016)
			(layers "F.Cu" "F.Mask" "F.Paste")
			(net "SW_HDD_P11")
		)
		(pad "4" smd rect
			(at 0.65024 -0.9398 90)
			(size 0.4064 1.016)
			(layers "F.Cu" "F.Mask" "F.Paste")
			(net "GND")
		)
		(pad "5" smd rect
			(at 0 -0.9398 90)
			(size 0.4064 1.016)
			(layers "F.Cu" "F.Mask" "F.Paste")
			(net "SW_HDD_G11")
		)
		(pad "6" smd rect
			(at -0.65024 -0.9398 90)
			(size 0.4064 1.016)
			(layers "F.Cu" "F.Mask" "F.Paste")
			(net "SW_HDD_R11")
		)
	)
)
